# S9S_MB_2U (Grand Teton) — schematic netlist excerpt (pin names and nets, part order shuffled) for the footprints in the layout excerpt that follows; sources: Cadence DE-HDL packaged netlist, KiCad conversion of 03242023_DA0F0TMBIJ0_F0T_Motherboard_J_brd_V01_OCP.brd

PC1259  Q_CAP  22UF 16V 20% X6S  pkg C0805  page 299 : A = SW_P12V_PVCCIN_CPU1_FLT ; B = GND
PL17  Q_INDUCTOR  120NH/69A IND  pkg SMLF  page 297 : \1\ = SW_PVCCD_HV_CPU1_SW1 ; \2\ = PVCCD_HV_CPU1
PC1849  Q_CAP  22UF 16V 20% X6S  pkg C0805  page 258 : A = SW_P5V_AUX_FLT ; B = GND

(kicad_pcb
	(version 20260206)
	(generator "pcbnew")
	(generator_version "10.0")
	(general
		(thickness 1.6)
		(legacy_teardrops no)
	)
	(paper "A4")
	(title_block
		(title "03242023_DA0F0TMBIJ0_F0T_Motherboard_J_brd_V01_OCP.brd")
		(comment 1 "Grand Teton / footprints 581-583 of 6105")
	)
	(layers
		(0 "F.Cu" signal "TOP")
		(4 "In1.Cu" signal "GND")
		(6 "In2.Cu" signal "IN1")
		(8 "In3.Cu" signal "GND1")
		(10 "In4.Cu" signal "IN2")
		(12 "In5.Cu" signal "GND2")
		(14 "In6.Cu" signal "IN3")
		(16 "In7.Cu" signal "GND3")
		(18 "In8.Cu" signal "VCC")
		(20 "In9.Cu" signal "VCC1")
		(22 "In10.Cu" signal "GND4")
		(24 "In11.Cu" signal "IN4")
		(26 "In12.Cu" signal "GND5")
		(28 "In13.Cu" signal "IN5")
		(30 "In14.Cu" signal "GND6")
		(32 "In15.Cu" signal "IN6")
		(34 "In16.Cu" signal "GND7")
		(2 "B.Cu" signal "BOTTOM")
		(9 "F.Adhes" user "F.Adhesive")
		(11 "B.Adhes" user "B.Adhesive")
		(13 "F.Paste" user "Package Geometry/Pastemask Top")
		(15 "B.Paste" user "Package Geometry/Pastemask Bottom")
		(5 "F.SilkS" user "Ref Des/Silkscreen Top")
		(7 "B.SilkS" user "Ref Des/Silkscreen Bottom")
		(1 "F.Mask" user "Board Geometry/Soldermask Top")
		(3 "B.Mask" user "Board Geometry/Soldermask Bottom")
		(17 "Dwgs.User" user "User.Drawings")
		(19 "Cmts.User" user "User.Comments")
		(21 "Eco1.User" user "User.Eco1")
		(23 "Eco2.User" user "User.Eco2")
		(25 "Edge.Cuts" user "Board Geometry/Outline")
		(27 "Margin" user)
		(31 "F.CrtYd" user "Package Geometry/Place Bound Top")
		(29 "B.CrtYd" user "Package Geometry/Place Bound Bottom")
		(35 "F.Fab" user "Ref Des/Assembly Top")
		(33 "B.Fab" user "Ref Des/Assembly Bottom")
	)
	(footprint ""
		(layer "F.Cu")
		(at 463.215736 -385.742434 90)
		(property "Reference" "PC1849"
			(at 0 0 90)
			(layer "F.SilkS")
			(hide yes)
			(effects
				(font
					(size 1.27 1.27)
				)
			)
		)
		(property "Value" ""
			(at 0 0 90)
			(layer "F.Fab")
			(effects
				(font
					(size 1.27 1.27)
				)
			)
		)
		(duplicate_pad_numbers_are_jumpers no)
		(fp_line
			(start 1.524 -0.762)
			(end 1.524 0.762)
			(stroke
				(width 0.1524)
				(type default)
			)
			(layer "F.SilkS")
		)
		(fp_line
			(start -1.524 -0.762)
			(end 1.524 -0.762)
			(stroke
				(width 0.1524)
				(type default)
			)
			(layer "F.SilkS")
		)
		(fp_line
			(start 1.524 0.762)
			(end -1.524 0.762)
			(stroke
				(width 0.1524)
				(type default)
			)
			(layer "F.SilkS")
		)
		(fp_line
			(start -1.524 0.762)
			(end -1.524 -0.762)
			(stroke
				(width 0.1524)
				(type default)
			)
			(layer "F.SilkS")
		)
		(fp_line
			(start 1.1049 -0.724916)
			(end -1.1049 -0.724916)
			(stroke
				(width 0.1)
				(type default)
			)
			(layer "F.Fab")
		)
		(fp_line
			(start -1.1049 -0.724916)
			(end -1.1049 0.724916)
			(stroke
				(width 0.1)
				(type default)
			)
			(layer "F.Fab")
		)
		(fp_line
			(start 1.1049 0.724916)
			(end 1.1049 -0.724916)
			(stroke
				(width 0.1)
				(type default)
			)
			(layer "F.Fab")
		)
		(fp_line
			(start -1.1049 0.724916)
			(end 1.1049 0.724916)
			(stroke
				(width 0.1)
				(type default)
			)
			(layer "F.Fab")
		)
		(pad "1" smd rect
			(at -0.889 0 270)
			(size 1.016 1.27)
			(layers "F.Cu" "F.Mask" "F.Paste")
			(net "SW_P5V_AUX_FLT")
		)
		(pad "2" smd rect
			(at 0.889 0 270)
			(size 1.016 1.27)
			(layers "F.Cu" "F.Mask" "F.Paste")
			(net "GND")
		)
	)
	(footprint ""
		(layer "F.Cu")
		(at 62.35446 -165.11397)
		(property "Reference" "PL17"
			(at -4.10718 -4.488688 0)
			(unlocked yes)
			(layer "F.SilkS")
			(effects
				(font
					(size 0.7874 0.5842)
					(thickness 0.1524)
				)
				(justify left)
			)
		)
		(property "Value" ""
			(at 0 0 0)
			(layer "F.Fab")
			(effects
				(font
					(size 1.27 1.27)
				)
			)
		)
		(duplicate_pad_numbers_are_jumpers no)
		(fp_line
			(start -3.24993 -3.24993)
			(end 3.24993 -3.24993)
			(stroke
				(width 0.1524)
				(type default)
			)
			(layer "F.SilkS")
		)
		(fp_line
			(start -3.24993 -2.2352)
			(end -3.24993 -3.24993)
			(stroke
				(width 0.1524)
				(type default)
			)
			(layer "F.SilkS")
		)
		(fp_line
			(start -3.24993 3.24993)
			(end -3.24993 2.2352)
			(stroke
				(width 0.1524)
				(type default)
			)
			(layer "F.SilkS")
		)
		(fp_line
			(start 3.24993 -3.24993)
			(end 3.24993 -2.2352)
			(stroke
				(width 0.1524)
				(type default)
			)
			(layer "F.SilkS")
		)
		(fp_line
			(start 3.24993 2.2352)
			(end 3.24993 3.24993)
			(stroke
				(width 0.1524)
				(type default)
			)
			(layer "F.SilkS")
		)
		(fp_line
			(start 3.24993 3.24993)
			(end -3.24993 3.24993)
			(stroke
				(width 0.1524)
				(type default)
			)
			(layer "F.SilkS")
		)
		(fp_line
			(start -3.24993 -3.24993)
			(end 3.24993 -3.24993)
			(stroke
				(width 0.1)
				(type default)
			)
			(layer "F.Fab")
		)
		(fp_line
			(start -3.24993 3.24993)
			(end -3.24993 -3.24993)
			(stroke
				(width 0.1)
				(type default)
			)
			(layer "F.Fab")
		)
		(fp_line
			(start 3.24993 -3.24993)
			(end 3.24993 3.24993)
			(stroke
				(width 0.1)
				(type default)
			)
			(layer "F.Fab")
		)
		(fp_line
			(start 3.24993 3.24993)
			(end -3.24993 3.24993)
			(stroke
				(width 0.1)
				(type default)
			)
			(layer "F.Fab")
		)
		(pad "1" smd rect
			(at -2.29997 0)
			(size 2.0066 4.2164)
			(layers "F.Cu" "F.Mask" "F.Paste")
			(net "SW_PVCCD_HV_CPU1_SW1")
		)
		(pad "2" smd rect
			(at 2.29997 0)
			(size 2.0066 4.2164)
			(layers "F.Cu" "F.Mask" "F.Paste")
			(net "PVCCD_HV_CPU1")
		)
	)
	(footprint ""
		(layer "F.Cu")
		(at 126.396242 -354.844858)
		(property "Reference" "PC1259"
			(at 0 0 0)
			(layer "F.SilkS")
			(hide yes)
			(effects
				(font
					(size 1.27 1.27)
				)
			)
		)
		(property "Value" ""
			(at 0 0 0)
			(layer "F.Fab")
			(effects
				(font
					(size 1.27 1.27)
				)
			)
		)
		(duplicate_pad_numbers_are_jumpers no)
		(fp_line
			(start -1.524 -0.762)
			(end 1.524 -0.762)
			(stroke
				(width 0.1524)
				(type default)
			)
			(layer "F.SilkS")
		)
		(fp_line
			(start -1.524 0.762)
			(end -1.524 -0.762)
			(stroke
				(width 0.1524)
				(type default)
			)
			(layer "F.SilkS")
		)
		(fp_line
			(start 1.524 -0.762)
			(end 1.524 0.762)
			(stroke
				(width 0.1524)
				(type default)
			)
			(layer "F.SilkS")
		)
		(fp_line
			(start 1.524 0.762)
			(end -1.524 0.762)
			(stroke
				(width 0.1524)
				(type default)
			)
			(layer "F.SilkS")
		)
		(fp_line
			(start -1.1049 -0.724916)
			(end -1.1049 0.724916)
			(stroke
				(width 0.1)
				(type default)
			)
			(layer "F.Fab")
		)
		(fp_line
			(start -1.1049 0.724916)
			(end 1.1049 0.724916)
			(stroke
				(width 0.1)
				(type default)
			)
			(layer "F.Fab")
		)
		(fp_line
			(start 1.1049 -0.724916)
			(end -1.1049 -0.724916)
			(stroke
				(width 0.1)
				(type default)
			)
			(layer "F.Fab")
		)
		(fp_line
			(start 1.1049 0.724916)
			(end 1.1049 -0.724916)
			(stroke
				(width 0.1)
				(type default)
			)
			(layer "F.Fab")
		)
		(pad "1" smd rect
			(at -0.889 0 180)
			(size 1.016 1.27)
			(layers "F.Cu" "F.Mask" "F.Paste")
			(net "SW_P12V_PVCCIN_CPU1_FLT")
		)
		(pad "2" smd rect
			(at 0.889 0 180)
			(size 1.016 1.27)
			(layers "F.Cu" "F.Mask" "F.Paste")
			(net "GND")
		)
	)
)
